# T6G (Grand Teton) — schematic netlist excerpt (pin names and nets, part order shuffled) for the footprints in the layout excerpt that follows; sources: Cadence DE-HDL packaged netlist, KiCad conversion of 04192023_DAF0TMB3IC0_F0TG_MB_C_brd_V02_OCP.brd

R3004  Q_RES  2.2K 5% EMPTY  pkg 0402LF  page 151 : A = SMB_2_BMC_GPU_SDA ; B = P3V3_AUX

U213  IML3112Y2B000NCG8  IML3112-Y2B000NCG8 EMPTY  pkg DFN8_TH_0-5_2X3XC  page 161
  LSDA_0  = SMB_APML_CPU0_R_SDA
  HSDA  = SMB_CPU0_CPU1_APML_MUX1_SDA
  HSCL  = SMB_CPU0_CPU1_APML_MUX1_SCL
  LSCL_0  = SMB_APML_CPU0_R_SCL
  VDD  = PVDD18_S5_P0
  LSCL_1  = SMB_APML_CPU1_R_SCL
  VIO  = I3C_MUX_CPU0_VIO
  \lsda_1||hsa\  = SMB_APML_CPU1_R_SDA
  TH_GND  = GND

(kicad_pcb
	(version 20260206)
	(generator "pcbnew")
	(generator_version "10.0")
	(general
		(thickness 1.6)
		(legacy_teardrops no)
	)
	(paper "A4")
	(title_block
		(title "04192023_DAF0TMB3IC0_F0TG_MB_C_brd_V02_OCP.brd")
		(comment 1 "Grand Teton / footprints 6347-6348 of 8354")
	)
	(layers
		(0 "F.Cu" signal "TOP")
		(4 "In1.Cu" signal "GND")
		(6 "In2.Cu" signal "IN1")
		(8 "In3.Cu" signal "GND1")
		(10 "In4.Cu" signal "IN2")
		(12 "In5.Cu" signal "GND2")
		(14 "In6.Cu" signal "IN3")
		(16 "In7.Cu" signal "GND3")
		(18 "In8.Cu" signal "VCC")
		(20 "In9.Cu" signal "VCC1")
		(22 "In10.Cu" signal "GND4")
		(24 "In11.Cu" signal "IN4")
		(26 "In12.Cu" signal "GND5")
		(28 "In13.Cu" signal "IN5")
		(30 "In14.Cu" signal "GND6")
		(32 "In15.Cu" signal "IN6")
		(34 "In16.Cu" signal "GND7")
		(2 "B.Cu" signal "BOTTOM")
		(9 "F.Adhes" user "F.Adhesive")
		(11 "B.Adhes" user "B.Adhesive")
		(13 "F.Paste" user "Package Geometry/Pastemask Top")
		(15 "B.Paste" user "Package Geometry/Pastemask Bottom")
		(5 "F.SilkS" user "Ref Des/Silkscreen Top")
		(7 "B.SilkS" user "Ref Des/Silkscreen Bottom")
		(1 "F.Mask" user "Board Geometry/Soldermask Top")
		(3 "B.Mask" user "Board Geometry/Soldermask Bottom")
		(17 "Dwgs.User" user "User.Drawings")
		(19 "Cmts.User" user "User.Comments")
		(21 "Eco1.User" user "User.Eco1")
		(23 "Eco2.User" user "User.Eco2")
		(25 "Edge.Cuts" user "Board Geometry/Outline")
		(27 "Margin" user)
		(31 "F.CrtYd" user "Package Geometry/Place Bound Top")
		(29 "B.CrtYd" user "Package Geometry/Place Bound Bottom")
		(35 "F.Fab" user "Ref Des/Assembly Top")
		(33 "B.Fab" user "Ref Des/Assembly Bottom")
	)
	(footprint ""
		(layer "B.Cu")
		(at 231.138476 -236.074204 90)
		(property "Reference" "U213"
			(at -2.063242 -3.25882 270)
			(unlocked yes)
			(layer "B.SilkS")
			(effects
				(font
					(size 0.7874 0.5842)
					(thickness 0.1524)
				)
				(justify left mirror)
			)
		)
		(property "Value" ""
			(at 0 0 90)
			(layer "B.Fab")
			(effects
				(font
					(size 1.27 1.27)
				)
				(justify mirror)
			)
		)
		(duplicate_pad_numbers_are_jumpers no)
		(fp_line
			(start 1.781302 -1.012698)
			(end -1.781302 -1.012698)
			(stroke
				(width 0.1524)
				(type default)
			)
			(layer "B.SilkS")
		)
		(fp_line
			(start -1.781302 -1.012698)
			(end -1.781302 1.012698)
			(stroke
				(width 0.1524)
				(type default)
			)
			(layer "B.SilkS")
		)
		(fp_line
			(start 1.781302 1.012698)
			(end 1.781302 -1.012698)
			(stroke
				(width 0.1524)
				(type default)
			)
			(layer "B.SilkS")
		)
		(fp_line
			(start 0 1.012698)
			(end 1.781302 1.012698)
			(stroke
				(width 0.1524)
				(type default)
			)
			(layer "B.SilkS")
		)
		(fp_line
			(start -1.781302 1.012698)
			(end 0 1.012698)
			(stroke
				(width 0.1524)
				(type default)
			)
			(layer "B.SilkS")
		)
		(fp_poly
			(pts
				(xy 1.214374 -1.333754) (xy 1.187704 -2.469134) (xy 0.290068 -1.993646)
			)
			(stroke
				(width 0)
				(type default)
			)
			(fill yes)
			(layer "B.SilkS")
		)
		(fp_line
			(start 1.500124 -0.999998)
			(end -1.500124 -0.999998)
			(stroke
				(width 0.1)
				(type default)
			)
			(layer "B.Fab")
		)
		(fp_line
			(start -1.500124 -0.999998)
			(end -1.500124 0.999998)
			(stroke
				(width 0.1)
				(type default)
			)
			(layer "B.Fab")
		)
		(fp_line
			(start 1.500124 0.999998)
			(end 1.500124 -0.999998)
			(stroke
				(width 0.1)
				(type default)
			)
			(layer "B.Fab")
		)
		(fp_line
			(start 0 0.999998)
			(end 1.500124 0.999998)
			(stroke
				(width 0.1)
				(type default)
			)
			(layer "B.Fab")
		)
		(fp_line
			(start -1.500124 0.999998)
			(end 0 0.999998)
			(stroke
				(width 0.1)
				(type default)
			)
			(layer "B.Fab")
		)
		(fp_poly
			(pts
				(xy 2.9972 -1.258062) (xy 2.9972 -0.242062) (xy 1.9812 -0.750062)
			)
			(stroke
				(width 0)
				(type default)
			)
			(fill yes)
			(layer "B.Fab")
		)
		(pad "1" smd rect
			(at 1.374902 -0.750062)
			(size 0.254 0.5588)
			(layers "B.Cu" "B.Mask" "B.Paste")
			(net "SMB_APML_CPU0_R_SDA")
		)
		(pad "2" smd rect
			(at 1.374902 -0.249936)
			(size 0.254 0.5588)
			(layers "B.Cu" "B.Mask" "B.Paste")
			(net "SMB_CPU0_CPU1_APML_MUX1_SDA")
		)
		(pad "3" smd rect
			(at 1.374902 0.249936)
			(size 0.254 0.5588)
			(layers "B.Cu" "B.Mask" "B.Paste")
			(net "SMB_CPU0_CPU1_APML_MUX1_SCL")
		)
		(pad "4" smd rect
			(at 1.374902 0.750062)
			(size 0.254 0.5588)
			(layers "B.Cu" "B.Mask" "B.Paste")
			(net "SMB_APML_CPU0_R_SCL")
		)
		(pad "5" smd rect
			(at -1.374902 0.750062)
			(size 0.254 0.5588)
			(layers "B.Cu" "B.Mask" "B.Paste")
			(net "PVDD18_S5_P0")
		)
		(pad "6" smd rect
			(at -1.374902 0.249936)
			(size 0.254 0.5588)
			(layers "B.Cu" "B.Mask" "B.Paste")
			(net "SMB_APML_CPU1_R_SCL")
		)
		(pad "7" smd rect
			(at -1.374902 -0.249936)
			(size 0.254 0.5588)
			(layers "B.Cu" "B.Mask" "B.Paste")
			(net "I3C_MUX_CPU0_VIO")
		)
		(pad "8" smd rect
			(at -1.374902 -0.750062)
			(size 0.254 0.5588)
			(layers "B.Cu" "B.Mask" "B.Paste")
			(net "SMB_APML_CPU1_R_SDA")
		)
		(pad "9" smd circle
			(at 0 0 270)
			(size 0 0)
			(layers "B.Cu" "B.Mask" "B.Paste")
			(net "GND")
		)
		(zone
			(layer "B.Cu")
			(hatch none 0.5)
			(connect_pads
				(clearance 0)
			)
			(min_thickness 0.25)
			(keepout
				(tracks not_allowed)
				(vias allowed)
				(pads allowed)
				(copperpour not_allowed)
				(footprints allowed)
			)
			(placement
				(enabled no)
				(sheetname "")
			)
			(fill
				(thermal_gap 0.5)
				(thermal_bridge_width 0.5)
				(island_removal_mode 0)
			)
			(polygon
				(pts
					(xy 232.129076 -237.115604) (xy 230.147876 -237.115604) (xy 230.147876 -236.556804) (xy 230.325676 -236.556804)
					(xy 230.325676 -236.887004) (xy 231.951276 -236.887004) (xy 231.951276 -235.261404) (xy 230.325676 -235.261404)
					(xy 230.325676 -236.531404) (xy 230.147876 -236.531404) (xy 230.147876 -235.032804) (xy 232.129076 -235.032804)
				)
			)
		)
	)
	(footprint ""
		(layer "B.Cu")
		(at 155.02001 -16.851122 -90)
		(property "Reference" "R3004"
			(at 0 0 90)
			(layer "B.SilkS")
			(hide yes)
			(effects
				(font
					(size 1.27 1.27)
				)
				(justify mirror)
			)
		)
		(property "Value" ""
			(at 0 0 90)
			(layer "B.Fab")
			(effects
				(font
					(size 1.27 1.27)
				)
				(justify mirror)
			)
		)
		(duplicate_pad_numbers_are_jumpers no)
		(fp_line
			(start -0.7874 0.4064)
			(end 0.7874 0.4064)
			(stroke
				(width 0.1524)
				(type default)
			)
			(layer "B.SilkS")
		)
		(fp_line
			(start 0.7874 0.4064)
			(end 0.7874 -0.4064)
			(stroke
				(width 0.1524)
				(type default)
			)
			(layer "B.SilkS")
		)
		(fp_line
			(start -0.7874 -0.4064)
			(end -0.7874 0.4064)
			(stroke
				(width 0.1524)
				(type default)
			)
			(layer "B.SilkS")
		)
		(fp_line
			(start 0.7874 -0.4064)
			(end -0.7874 -0.4064)
			(stroke
				(width 0.1524)
				(type default)
			)
			(layer "B.SilkS")
		)
		(fp_line
			(start -0.67945 0.3048)
			(end -0.120396 0.3048)
			(stroke
				(width 0.1)
				(type default)
			)
			(layer "B.Fab")
		)
		(fp_line
			(start -0.120396 0.3048)
			(end -0.120396 0.2794)
			(stroke
				(width 0.1)
				(type default)
			)
			(layer "B.Fab")
		)
		(fp_line
			(start 0.12065 0.3048)
			(end 0.67945 0.3048)
			(stroke
				(width 0.1)
				(type default)
			)
			(layer "B.Fab")
		)
		(fp_line
			(start 0.67945 0.3048)
			(end 0.67945 -0.305054)
			(stroke
				(width 0.1)
				(type default)
			)
			(layer "B.Fab")
		)
		(fp_line
			(start -0.120396 0.2794)
			(end 0.12065 0.2794)
			(stroke
				(width 0.1)
				(type default)
			)
			(layer "B.Fab")
		)
		(fp_line
			(start 0.12065 0.2794)
			(end 0.12065 0.3048)
			(stroke
				(width 0.1)
				(type default)
			)
			(layer "B.Fab")
		)
		(fp_line
			(start -0.12065 -0.2794)
			(end -0.12065 -0.3048)
			(stroke
				(width 0.1)
				(type default)
			)
			(layer "B.Fab")
		)
		(fp_line
			(start 0.12065 -0.2794)
			(end -0.12065 -0.2794)
			(stroke
				(width 0.1)
				(type default)
			)
			(layer "B.Fab")
		)
		(fp_line
			(start -0.67945 -0.3048)
			(end -0.67945 0.3048)
			(stroke
				(width 0.1)
				(type default)
			)
			(layer "B.Fab")
		)
		(fp_line
			(start -0.12065 -0.3048)
			(end -0.67945 -0.3048)
			(stroke
				(width 0.1)
				(type default)
			)
			(layer "B.Fab")
		)
		(fp_line
			(start 0.12065 -0.305054)
			(end 0.12065 -0.2794)
			(stroke
				(width 0.1)
				(type default)
			)
			(layer "B.Fab")
		)
		(fp_line
			(start 0.67945 -0.305054)
			(end 0.12065 -0.305054)
			(stroke
				(width 0.1)
				(type default)
			)
			(layer "B.Fab")
		)
		(pad "1" smd circle
			(at 0.40005 0 90)
			(size 0 0)
			(layers "B.Cu" "B.Mask" "B.Paste")
			(net "SMB_2_BMC_GPU_SDA")
		)
		(pad "2" smd circle
			(at -0.40005 0 90)
			(size 0 0)
			(layers "B.Cu" "B.Mask" "B.Paste")
			(net "P3V3_AUX")
		)
	)
)
